(kicad_pcb
	(version 20260206)
	(generator "pcbnew")
	(generator_version "10.0")
	(general
		(thickness 1.6)
		(legacy_teardrops no)
	)
	(paper "A4")
	(title_block
		(title "baseboard — 13948-1b.1110WZS1818.brd")
		(comment 1 "Honey Badger (Wiwynn) / footprints 2509-2517 of 2523")
	)
	(layers
		(0 "F.Cu" signal "TOP")
		(4 "In1.Cu" signal "L2GND")
		(6 "In2.Cu" signal "L3")
		(8 "In3.Cu" signal "L4VCC")
		(10 "In4.Cu" signal "L5VCC")
		(12 "In5.Cu" signal "L6")
		(14 "In6.Cu" signal "L7GND")
		(2 "B.Cu" signal "BOTTOM")
		(9 "F.Adhes" user "F.Adhesive")
		(11 "B.Adhes" user "B.Adhesive")
		(13 "F.Paste" user "Package Geometry/Pastemask Top")
		(15 "B.Paste" user "Package Geometry/Pastemask Bottom")
		(5 "F.SilkS" user "Ref Des/Silkscreen Top")
		(7 "B.SilkS" user "Ref Des/Silkscreen Bottom")
		(1 "F.Mask" user "Board Geometry/Soldermask Top")
		(3 "B.Mask" user "Board Geometry/Soldermask Bottom")
		(17 "Dwgs.User" user "User.Drawings")
		(19 "Cmts.User" user "User.Comments")
		(21 "Eco1.User" user "User.Eco1")
		(23 "Eco2.User" user "User.Eco2")
		(25 "Edge.Cuts" user "Board Geometry/Outline")
		(27 "Margin" user)
		(31 "F.CrtYd" user "Package Geometry/Place Bound Top")
		(29 "B.CrtYd" user "Package Geometry/Place Bound Bottom")
		(35 "F.Fab" user "Ref Des/Assembly Top")
		(33 "B.Fab" user "Ref Des/Assembly Bottom")
	)
	(footprint ""
		(layer "B.Cu")
		(at 108.020612 -217.297 -90)
		(property "Reference" "SR913"
			(at 0 0 90)
			(layer "B.SilkS")
			(hide yes)
			(effects
				(font
					(size 1.27 1.27)
				)
				(justify mirror)
			)
		)
		(property "Value" "4K7R2F-GP"
			(at -0.064008 -3.993896 270)
			(unlocked yes)
			(layer "B.Fab")
			(hide yes)
			(effects
				(font
					(size 1.016 1.016)
					(thickness 0.1524)
				)
				(justify mirror)
			)
		)
		(property "Device Type" "R402H16"
			(at -0.064008 -5.517896 270)
			(unlocked yes)
			(layer "B.Fab")
			(hide yes)
			(effects
				(font
					(size 1.016 1.016)
					(thickness 0.1524)
				)
				(justify mirror)
			)
		)
		(duplicate_pad_numbers_are_jumpers no)
		(fp_line
			(start -0.508 -0.9398)
			(end 0.508 -0.9398)
			(stroke
				(width 0.1524)
				(type default)
			)
			(layer "B.SilkS")
		)
		(fp_line
			(start 0.508 -0.9398)
			(end 0.508 0.9398)
			(stroke
				(width 0.1524)
				(type default)
			)
			(layer "B.SilkS")
		)
		(fp_rect
			(start 0.508 0.9398)
			(end -0.508 -0.9398)
			(stroke
				(width 0)
				(type default)
			)
			(fill no)
			(layer "B.CrtYd")
		)
		(fp_rect
			(start 0.508 0.9398)
			(end -0.508 -0.9398)
			(stroke
				(width 0)
				(type default)
			)
			(fill no)
			(layer "B.Fab")
		)
		(pad "1" smd custom
			(at 0 -0.4445 90)
			(size 0.1397 0.1397)
			(layers "B.Cu" "B.Mask" "B.Paste")
			(net "REDV_I2C_SEL2B")
			(options
				(clearance outline)
				(anchor circle)
			)
			(primitives
				(gr_poly
					(pts
						(arc
							(start -0.1778 0.2794)
							(mid -0.249642 0.249642)
							(end -0.2794 0.1778)
						)
						(arc
							(start -0.2794 -0.1778)
							(mid -0.249642 -0.249642)
							(end -0.1778 -0.2794)
						)
						(arc
							(start 0.1778 -0.2794)
							(mid 0.249642 -0.249642)
							(end 0.2794 -0.1778)
						)
						(arc
							(start 0.2794 0.1778)
							(mid 0.249642 0.249642)
							(end 0.1778 0.2794)
						)
					)
					(width 0)
					(fill yes)
				)
			)
		)
		(pad "2" smd custom
			(at 0 0.4445 90)
			(size 0.1397 0.1397)
			(layers "B.Cu" "B.Mask" "B.Paste")
			(net "GND")
			(options
				(clearance outline)
				(anchor circle)
			)
			(primitives
				(gr_poly
					(pts
						(arc
							(start -0.1778 0.2794)
							(mid -0.249642 0.249642)
							(end -0.2794 0.1778)
						)
						(arc
							(start -0.2794 -0.1778)
							(mid -0.249642 -0.249642)
							(end -0.1778 -0.2794)
						)
						(arc
							(start 0.1778 -0.2794)
							(mid 0.249642 -0.249642)
							(end 0.2794 -0.1778)
						)
						(arc
							(start 0.2794 0.1778)
							(mid 0.249642 0.249642)
							(end 0.1778 0.2794)
						)
					)
					(width 0)
					(fill yes)
				)
			)
		)
	)
	(footprint ""
		(layer "B.Cu")
		(at 117.48897 -87.884)
		(property "Reference" "STP108"
			(at 0 0 0)
			(layer "B.SilkS")
			(hide yes)
			(effects
				(font
					(size 1.27 1.27)
				)
				(justify mirror)
			)
		)
		(property "Value" "TPAD28"
			(at -0.0127 -1.8034 0)
			(unlocked yes)
			(layer "B.Fab")
			(hide yes)
			(effects
				(font
					(size 1.016 1.016)
					(thickness 0.1524)
				)
				(justify mirror)
			)
		)
		(property "Device Type" "TPAD28"
			(at -0.0127 -3.3274 0)
			(unlocked yes)
			(layer "B.Fab")
			(hide yes)
			(effects
				(font
					(size 1.016 1.016)
					(thickness 0.1524)
				)
				(justify mirror)
			)
		)
		(duplicate_pad_numbers_are_jumpers no)
		(fp_poly
			(pts
				(arc
					(start 0.3556 0)
					(mid -0.3556 0)
					(end 0.3556 0)
				)
			)
			(stroke
				(width 0)
				(type default)
			)
			(fill no)
			(layer "B.CrtYd")
		)
		(fp_poly
			(pts
				(arc
					(start 0.6096 0)
					(mid -0.6096 0)
					(end 0.6096 0)
				)
			)
			(stroke
				(width 0)
				(type default)
			)
			(fill no)
			(layer "B.Fab")
		)
		(pad "1" smd circle
			(at 0 0 180)
			(size 0.7112 0.7112)
			(layers "B.Cu" "B.Mask" "B.Paste")
			(net "TEST_MUX_41")
		)
	)
	(footprint ""
		(layer "B.Cu")
		(at 331.499464 -22.237192)
		(property "Reference" ""
			(at 0 0 0)
			(layer "B.SilkS")
			(hide yes)
			(effects
				(font
					(size 1.27 1.27)
				)
				(justify mirror)
			)
		)
		(property "Value" "*"
			(at 5.5753 -0.4572 0)
			(unlocked yes)
			(layer "B.Fab")
			(hide yes)
			(effects
				(font
					(size 1.016 1.016)
					(thickness 0.1524)
				)
				(justify mirror)
			)
		)
		(duplicate_pad_numbers_are_jumpers no)
		(fp_poly
			(pts
				(arc
					(start 4.3053 0)
					(mid -4.3053 0)
					(end 4.3053 0)
				)
			)
			(stroke
				(width 0)
				(type default)
			)
			(fill no)
			(layer "B.CrtYd")
		)
		(fp_poly
			(pts
				(arc
					(start 4.3053 0)
					(mid -4.3053 0)
					(end 4.3053 0)
				)
			)
			(stroke
				(width 0)
				(type default)
			)
			(fill no)
			(layer "B.Fab")
		)
		(pad "1" smd custom
			(at 2.95275 0 180)
			(size 2.000013 2.000013)
			(layers "B.Cu" "B.Mask" "B.Paste")
			(net "Net_53")
			(options
				(clearance outline)
				(anchor circle)
			)
			(primitives
				(gr_poly
					(pts
						(arc
							(start 4.0005 -0.00254)
							(mid -4.000501 0)
							(end 4.0005 0.00254)
						)
						(arc
							(start 1.905 0.00254)
							(mid -1.905002 0)
							(end 1.905 -0.00254)
						)
					)
					(width 0)
					(fill yes)
				)
			)
		)
	)
	(footprint ""
		(layer "B.Cu")
		(at 160.147 -89.154)
		(property "Reference" "PC178"
			(at 0 0 0)
			(layer "B.SilkS")
			(hide yes)
			(effects
				(font
					(size 1.27 1.27)
				)
				(justify mirror)
			)
		)
		(property "Value" "SC22U6D3V3MX-1-GP"
			(at 0 -2.8194 0)
			(unlocked yes)
			(layer "B.Fab")
			(hide yes)
			(effects
				(font
					(size 1.016 1.016)
					(thickness 0.1524)
				)
				(justify mirror)
			)
		)
		(property "Device Type" "C603H40"
			(at 0 -4.3434 0)
			(unlocked yes)
			(layer "B.Fab")
			(hide yes)
			(effects
				(font
					(size 1.016 1.016)
					(thickness 0.1524)
				)
				(justify mirror)
			)
		)
		(duplicate_pad_numbers_are_jumpers no)
		(fp_line
			(start -0.508 0)
			(end 0.508 0)
			(stroke
				(width 0.2032)
				(type default)
			)
			(layer "B.SilkS")
		)
		(fp_rect
			(start 0.5842 1.3335)
			(end -0.5842 -1.3335)
			(stroke
				(width 0)
				(type default)
			)
			(fill no)
			(layer "B.CrtYd")
		)
		(fp_rect
			(start 0.5842 1.3335)
			(end -0.5842 -1.3335)
			(stroke
				(width 0)
				(type default)
			)
			(fill no)
			(layer "B.Fab")
		)
		(pad "1" smd custom
			(at 0 -0.762 180)
			(size 0.2159 0.2159)
			(layers "B.Cu" "B.Mask" "B.Paste")
			(net "P0V9_E")
			(options
				(clearance outline)
				(anchor circle)
			)
			(primitives
				(gr_poly
					(pts
						(arc
							(start -0.3302 0.4318)
							(mid -0.402042 0.402042)
							(end -0.4318 0.3302)
						)
						(arc
							(start -0.4318 -0.3302)
							(mid -0.402042 -0.402042)
							(end -0.3302 -0.4318)
						)
						(arc
							(start 0.3302 -0.4318)
							(mid 0.402042 -0.402042)
							(end 0.4318 -0.3302)
						)
						(arc
							(start 0.4318 0.3302)
							(mid 0.402042 0.402042)
							(end 0.3302 0.4318)
						)
					)
					(width 0)
					(fill yes)
				)
			)
		)
		(pad "2" smd custom
			(at 0 0.762 180)
			(size 0.2159 0.2159)
			(layers "B.Cu" "B.Mask" "B.Paste")
			(net "GND")
			(options
				(clearance outline)
				(anchor circle)
			)
			(primitives
				(gr_poly
					(pts
						(arc
							(start -0.3302 0.4318)
							(mid -0.402042 0.402042)
							(end -0.4318 0.3302)
						)
						(arc
							(start -0.4318 -0.3302)
							(mid -0.402042 -0.402042)
							(end -0.3302 -0.4318)
						)
						(arc
							(start 0.3302 -0.4318)
							(mid 0.402042 -0.402042)
							(end 0.4318 -0.3302)
						)
						(arc
							(start 0.4318 0.3302)
							(mid 0.402042 0.402042)
							(end 0.3302 0.4318)
						)
					)
					(width 0)
					(fill yes)
				)
			)
		)
	)
	(footprint ""
		(layer "B.Cu")
		(at 263.271 -16.891 180)
		(property "Reference" "C335"
			(at 0 0 0)
			(layer "B.SilkS")
			(hide yes)
			(effects
				(font
					(size 1.27 1.27)
				)
				(justify mirror)
			)
		)
		(property "Value" "SC1U10V3KX-4GP-U"
			(at 0 -2.8194 180)
			(unlocked yes)
			(layer "B.Fab")
			(hide yes)
			(effects
				(font
					(size 1.016 1.016)
					(thickness 0.1524)
				)
				(justify mirror)
			)
		)
		(property "Device Type" "C603H36"
			(at 0 -4.3434 180)
			(unlocked yes)
			(layer "B.Fab")
			(hide yes)
			(effects
				(font
					(size 1.016 1.016)
					(thickness 0.1524)
				)
				(justify mirror)
			)
		)
		(duplicate_pad_numbers_are_jumpers no)
		(fp_line
			(start -0.508 0)
			(end 0.508 0)
			(stroke
				(width 0.2032)
				(type default)
			)
			(layer "B.SilkS")
		)
		(fp_rect
			(start 0.5842 1.3335)
			(end -0.5842 -1.3335)
			(stroke
				(width 0)
				(type default)
			)
			(fill no)
			(layer "B.CrtYd")
		)
		(fp_rect
			(start 0.5842 1.3335)
			(end -0.5842 -1.3335)
			(stroke
				(width 0)
				(type default)
			)
			(fill no)
			(layer "B.Fab")
		)
		(pad "1" smd custom
			(at 0 -0.762)
			(size 0.2159 0.2159)
			(layers "B.Cu" "B.Mask" "B.Paste")
			(net "P5V_USB")
			(options
				(clearance outline)
				(anchor circle)
			)
			(primitives
				(gr_poly
					(pts
						(arc
							(start -0.3302 0.4318)
							(mid -0.402042 0.402042)
							(end -0.4318 0.3302)
						)
						(arc
							(start -0.4318 -0.3302)
							(mid -0.402042 -0.402042)
							(end -0.3302 -0.4318)
						)
						(arc
							(start 0.3302 -0.4318)
							(mid 0.402042 -0.402042)
							(end 0.4318 -0.3302)
						)
						(arc
							(start 0.4318 0.3302)
							(mid 0.402042 0.402042)
							(end 0.3302 0.4318)
						)
					)
					(width 0)
					(fill yes)
				)
			)
		)
		(pad "2" smd custom
			(at 0 0.762)
			(size 0.2159 0.2159)
			(layers "B.Cu" "B.Mask" "B.Paste")
			(net "GND")
			(options
				(clearance outline)
				(anchor circle)
			)
			(primitives
				(gr_poly
					(pts
						(arc
							(start -0.3302 0.4318)
							(mid -0.402042 0.402042)
							(end -0.4318 0.3302)
						)
						(arc
							(start -0.4318 -0.3302)
							(mid -0.402042 -0.402042)
							(end -0.3302 -0.4318)
						)
						(arc
							(start 0.3302 -0.4318)
							(mid 0.402042 -0.402042)
							(end 0.4318 -0.3302)
						)
						(arc
							(start 0.4318 0.3302)
							(mid 0.402042 0.402042)
							(end 0.3302 0.4318)
						)
					)
					(width 0)
					(fill yes)
				)
			)
		)
	)
	(footprint ""
		(layer "B.Cu")
		(at 105.489756 -40.3479)
		(property "Reference" "SC1042"
			(at 0 0 0)
			(layer "B.SilkS")
			(hide yes)
			(effects
				(font
					(size 1.27 1.27)
				)
				(justify mirror)
			)
		)
		(property "Value" "SCD1U16V2KX-3GP"
			(at -1.1811 -2.7051 0)
			(unlocked yes)
			(layer "B.Fab")
			(hide yes)
			(effects
				(font
					(size 1.016 1.016)
					(thickness 0.1524)
				)
				(justify mirror)
			)
		)
		(property "Device Type" "C402H22"
			(at -1.1811 -4.2291 0)
			(unlocked yes)
			(layer "B.Fab")
			(hide yes)
			(effects
				(font
					(size 1.016 1.016)
					(thickness 0.1524)
				)
				(justify mirror)
			)
		)
		(duplicate_pad_numbers_are_jumpers no)
		(fp_rect
			(start 0.4318 0.9525)
			(end -0.4318 -0.9525)
			(stroke
				(width 0)
				(type default)
			)
			(fill no)
			(layer "B.CrtYd")
		)
		(fp_rect
			(start 0.4318 0.9525)
			(end -0.4318 -0.9525)
			(stroke
				(width 0)
				(type default)
			)
			(fill no)
			(layer "B.Fab")
		)
		(pad "1" smd custom
			(at 0 -0.4445 180)
			(size 0.1524 0.1524)
			(layers "B.Cu" "B.Mask" "B.Paste")
			(net "P0V955_C")
			(options
				(clearance outline)
				(anchor circle)
			)
			(primitives
				(gr_poly
					(pts
						(arc
							(start 0.3048 0.2032)
							(mid 0.275042 0.275042)
							(end 0.2032 0.3048)
						)
						(arc
							(start -0.2032 0.3048)
							(mid -0.275042 0.275042)
							(end -0.3048 0.2032)
						)
						(arc
							(start -0.3048 -0.2032)
							(mid -0.275042 -0.275042)
							(end -0.2032 -0.3048)
						)
						(arc
							(start 0.2032 -0.3048)
							(mid 0.275042 -0.275042)
							(end 0.3048 -0.2032)
						)
					)
					(width 0)
					(fill yes)
				)
			)
		)
		(pad "2" smd custom
			(at 0 0.4445 180)
			(size 0.1524 0.1524)
			(layers "B.Cu" "B.Mask" "B.Paste")
			(net "GND")
			(options
				(clearance outline)
				(anchor circle)
			)
			(primitives
				(gr_poly
					(pts
						(arc
							(start 0.3048 0.2032)
							(mid 0.275042 0.275042)
							(end 0.2032 0.3048)
						)
						(arc
							(start -0.2032 0.3048)
							(mid -0.275042 0.275042)
							(end -0.3048 0.2032)
						)
						(arc
							(start -0.3048 -0.2032)
							(mid -0.275042 -0.275042)
							(end -0.2032 -0.3048)
						)
						(arc
							(start 0.2032 -0.3048)
							(mid 0.275042 -0.275042)
							(end 0.3048 -0.2032)
						)
					)
					(width 0)
					(fill yes)
				)
			)
		)
	)
	(footprint ""
		(layer "B.Cu")
		(at 118.68277 -87.0204)
		(property "Reference" "STP64"
			(at 0 0 0)
			(layer "B.SilkS")
			(hide yes)
			(effects
				(font
					(size 1.27 1.27)
				)
				(justify mirror)
			)
		)
		(property "Value" "TPAD28"
			(at -0.0127 -1.8034 0)
			(unlocked yes)
			(layer "B.Fab")
			(hide yes)
			(effects
				(font
					(size 1.016 1.016)
					(thickness 0.1524)
				)
				(justify mirror)
			)
		)
		(property "Device Type" "TPAD28"
			(at -0.0127 -3.3274 0)
			(unlocked yes)
			(layer "B.Fab")
			(hide yes)
			(effects
				(font
					(size 1.016 1.016)
					(thickness 0.1524)
				)
				(justify mirror)
			)
		)
		(duplicate_pad_numbers_are_jumpers no)
		(fp_poly
			(pts
				(arc
					(start 0.3556 0)
					(mid -0.3556 0)
					(end 0.3556 0)
				)
			)
			(stroke
				(width 0)
				(type default)
			)
			(fill no)
			(layer "B.CrtYd")
		)
		(fp_poly
			(pts
				(arc
					(start 0.6096 0)
					(mid -0.6096 0)
					(end 0.6096 0)
				)
			)
			(stroke
				(width 0)
				(type default)
			)
			(fill no)
			(layer "B.Fab")
		)
		(pad "1" smd circle
			(at 0 0 180)
			(size 0.7112 0.7112)
			(layers "B.Cu" "B.Mask" "B.Paste")
			(net "EXP_TEST_MUX26")
		)
	)
	(footprint ""
		(layer "B.Cu")
		(at 325.374 -177.8)
		(property "Reference" "R434"
			(at 0 0 0)
			(layer "B.SilkS")
			(hide yes)
			(effects
				(font
					(size 1.27 1.27)
				)
				(justify mirror)
			)
		)
		(property "Value" "3K3R2F-2-GP"
			(at -0.064008 -3.993896 0)
			(unlocked yes)
			(layer "B.Fab")
			(hide yes)
			(effects
				(font
					(size 1.016 1.016)
					(thickness 0.1524)
				)
				(justify mirror)
			)
		)
		(property "Device Type" "R402H16"
			(at -0.064008 -5.517896 0)
			(unlocked yes)
			(layer "B.Fab")
			(hide yes)
			(effects
				(font
					(size 1.016 1.016)
					(thickness 0.1524)
				)
				(justify mirror)
			)
		)
		(duplicate_pad_numbers_are_jumpers no)
		(fp_line
			(start -0.508 -0.9398)
			(end 0.508 -0.9398)
			(stroke
				(width 0.1524)
				(type default)
			)
			(layer "B.SilkS")
		)
		(fp_line
			(start 0.508 -0.9398)
			(end 0.508 0.9398)
			(stroke
				(width 0.1524)
				(type default)
			)
			(layer "B.SilkS")
		)
		(fp_rect
			(start 0.508 0.9398)
			(end -0.508 -0.9398)
			(stroke
				(width 0)
				(type default)
			)
			(fill no)
			(layer "B.CrtYd")
		)
		(fp_rect
			(start 0.508 0.9398)
			(end -0.508 -0.9398)
			(stroke
				(width 0)
				(type default)
			)
			(fill no)
			(layer "B.Fab")
		)
		(pad "1" smd custom
			(at 0 -0.4445 180)
			(size 0.1397 0.1397)
			(layers "B.Cu" "B.Mask" "B.Paste")
			(net "ADC_P5V_STBY")
			(options
				(clearance outline)
				(anchor circle)
			)
			(primitives
				(gr_poly
					(pts
						(arc
							(start -0.1778 0.2794)
							(mid -0.249642 0.249642)
							(end -0.2794 0.1778)
						)
						(arc
							(start -0.2794 -0.1778)
							(mid -0.249642 -0.249642)
							(end -0.1778 -0.2794)
						)
						(arc
							(start 0.1778 -0.2794)
							(mid 0.249642 -0.249642)
							(end 0.2794 -0.1778)
						)
						(arc
							(start 0.2794 0.1778)
							(mid 0.249642 0.249642)
							(end 0.1778 0.2794)
						)
					)
					(width 0)
					(fill yes)
				)
			)
		)
		(pad "2" smd custom
			(at 0 0.4445 180)
			(size 0.1397 0.1397)
			(layers "B.Cu" "B.Mask" "B.Paste")
			(net "P5V_STBY")
			(options
				(clearance outline)
				(anchor circle)
			)
			(primitives
				(gr_poly
					(pts
						(arc
							(start -0.1778 0.2794)
							(mid -0.249642 0.249642)
							(end -0.2794 0.1778)
						)
						(arc
							(start -0.2794 -0.1778)
							(mid -0.249642 -0.249642)
							(end -0.1778 -0.2794)
						)
						(arc
							(start 0.1778 -0.2794)
							(mid 0.249642 -0.249642)
							(end 0.2794 -0.1778)
						)
						(arc
							(start 0.2794 0.1778)
							(mid 0.249642 0.249642)
							(end 0.1778 0.2794)
						)
					)
					(width 0)
					(fill yes)
				)
			)
		)
	)
	(footprint ""
		(layer "B.Cu")
		(at 274.193 -181.737 90)
		(property "Reference" "R359"
			(at 0 0 90)
			(layer "B.SilkS")
			(hide yes)
			(effects
				(font
					(size 1.27 1.27)
				)
				(justify mirror)
			)
		)
		(property "Value" "3K3R2F-2-GP"
			(at -0.064008 -3.993896 90)
			(unlocked yes)
			(layer "B.Fab")
			(hide yes)
			(effects
				(font
					(size 1.016 1.016)
					(thickness 0.1524)
				)
				(justify mirror)
			)
		)
		(property "Device Type" "R402H16"
			(at -0.064008 -5.517896 90)
			(unlocked yes)
			(layer "B.Fab")
			(hide yes)
			(effects
				(font
					(size 1.016 1.016)
					(thickness 0.1524)
				)
				(justify mirror)
			)
		)
		(duplicate_pad_numbers_are_jumpers no)
		(fp_line
			(start 0.508 -0.9398)
			(end 0.508 0.9398)
			(stroke
				(width 0.1524)
				(type default)
			)
			(layer "B.SilkS")
		)
		(fp_line
			(start -0.508 -0.9398)
			(end 0.508 -0.9398)
			(stroke
				(width 0.1524)
				(type default)
			)
			(layer "B.SilkS")
		)
		(fp_rect
			(start 0.508 0.9398)
			(end -0.508 -0.9398)
			(stroke
				(width 0)
				(type default)
			)
			(fill no)
			(layer "B.CrtYd")
		)
		(fp_rect
			(start 0.508 0.9398)
			(end -0.508 -0.9398)
			(stroke
				(width 0)
				(type default)
			)
			(fill no)
			(layer "B.Fab")
		)
		(pad "1" smd custom
			(at 0 -0.4445 270)
			(size 0.1397 0.1397)
			(layers "B.Cu" "B.Mask" "B.Paste")
			(net "P3V3_STBY")
			(options
				(clearance outline)
				(anchor circle)
			)
			(primitives
				(gr_poly
					(pts
						(arc
							(start -0.1778 0.2794)
							(mid -0.249642 0.249642)
							(end -0.2794 0.1778)
						)
						(arc
							(start -0.2794 -0.1778)
							(mid -0.249642 -0.249642)
							(end -0.1778 -0.2794)
						)
						(arc
							(start 0.1778 -0.2794)
							(mid 0.249642 -0.249642)
							(end 0.2794 -0.1778)
						)
						(arc
							(start 0.2794 0.1778)
							(mid 0.249642 0.249642)
							(end 0.1778 0.2794)
						)
					)
					(width 0)
					(fill yes)
				)
			)
		)
		(pad "2" smd custom
			(at 0 0.4445 270)
			(size 0.1397 0.1397)
			(layers "B.Cu" "B.Mask" "B.Paste")
			(net "ROMA5")
			(options
				(clearance outline)
				(anchor circle)
			)
			(primitives
				(gr_poly
					(pts
						(arc
							(start -0.1778 0.2794)
							(mid -0.249642 0.249642)
							(end -0.2794 0.1778)
						)
						(arc
							(start -0.2794 -0.1778)
							(mid -0.249642 -0.249642)
							(end -0.1778 -0.2794)
						)
						(arc
							(start 0.1778 -0.2794)
							(mid 0.249642 -0.249642)
							(end 0.2794 -0.1778)
						)
						(arc
							(start 0.2794 0.1778)
							(mid 0.249642 0.249642)
							(end 0.1778 0.2794)
						)
					)
					(width 0)
					(fill yes)
				)
			)
		)
	)
)
